(kicad_pcb
	(version 20260206)
	(generator "pcbnew")
	(generator_version "10.0")
	(general
		(thickness 1.6)
		(legacy_teardrops no)
	)
	(paper "A4")
	(title_block
		(title "01162023_DA0F0TEBIF0_F0T_Expander_BD_F_brd_V02_OCP.brd")
		(comment 1 "Grand Teton / footprints 2104-2109 of 9728")
	)
	(layers
		(0 "F.Cu" signal "TOP")
		(4 "In1.Cu" signal "GND")
		(6 "In2.Cu" signal "VCC")
		(8 "In3.Cu" signal "VCC1")
		(10 "In4.Cu" signal "GND1")
		(12 "In5.Cu" signal "IN1")
		(14 "In6.Cu" signal "GND2")
		(16 "In7.Cu" signal "IN2")
		(18 "In8.Cu" signal "GND3")
		(20 "In9.Cu" signal "IN3")
		(22 "In10.Cu" signal "GND4")
		(24 "In11.Cu" signal "IN4")
		(26 "In12.Cu" signal "GND5")
		(28 "In13.Cu" signal "IN5")
		(30 "In14.Cu" signal "GND6")
		(32 "In15.Cu" signal "IN6")
		(34 "In16.Cu" signal "GND7")
		(2 "B.Cu" signal "BOTTOM")
		(9 "F.Adhes" user "F.Adhesive")
		(11 "B.Adhes" user "B.Adhesive")
		(13 "F.Paste" user "Package Geometry/Pastemask Top")
		(15 "B.Paste" user "Package Geometry/Pastemask Bottom")
		(5 "F.SilkS" user "Ref Des/Silkscreen Top")
		(7 "B.SilkS" user "Ref Des/Silkscreen Bottom")
		(1 "F.Mask" user "Board Geometry/Soldermask Top")
		(3 "B.Mask" user "Board Geometry/Soldermask Bottom")
		(17 "Dwgs.User" user "User.Drawings")
		(19 "Cmts.User" user "User.Comments")
		(21 "Eco1.User" user "User.Eco1")
		(23 "Eco2.User" user "User.Eco2")
		(25 "Edge.Cuts" user "Board Geometry/Outline")
		(27 "Margin" user)
		(31 "F.CrtYd" user "Package Geometry/Place Bound Top")
		(29 "B.CrtYd" user "Package Geometry/Place Bound Bottom")
		(35 "F.Fab" user "Ref Des/Assembly Top")
		(33 "B.Fab" user "Ref Des/Assembly Bottom")
	)
	(footprint ""
		(layer "F.Cu")
		(at 252.775466 -69.47916 180)
		(property "Reference" "PU111"
			(at -1.835404 3.92684 90)
			(unlocked yes)
			(layer "F.SilkS")
			(effects
				(font
					(size 0.7874 0.5842)
					(thickness 0.1524)
				)
			)
		)
		(property "Value" ""
			(at 0 0 180)
			(layer "F.Fab")
			(effects
				(font
					(size 1.27 1.27)
				)
			)
		)
		(duplicate_pad_numbers_are_jumpers no)
		(fp_line
			(start 1.239774 1.495298)
			(end -1.239774 1.495298)
			(stroke
				(width 0.1524)
				(type default)
			)
			(layer "F.SilkS")
		)
		(fp_line
			(start 1.239774 -1.495298)
			(end 1.239774 1.495298)
			(stroke
				(width 0.1524)
				(type default)
			)
			(layer "F.SilkS")
		)
		(fp_line
			(start -1.239774 1.495298)
			(end -1.239774 -1.495298)
			(stroke
				(width 0.1524)
				(type default)
			)
			(layer "F.SilkS")
		)
		(fp_line
			(start -1.239774 -1.495298)
			(end 1.239774 -1.495298)
			(stroke
				(width 0.1524)
				(type default)
			)
			(layer "F.SilkS")
		)
		(fp_poly
			(pts
				(xy -1.68021 -2.025904) (xy -2.398522 -1.307338) (xy -1.3208 -0.948182)
			)
			(stroke
				(width 0)
				(type default)
			)
			(fill yes)
			(layer "F.SilkS")
		)
		(fp_line
			(start 0.8001 1.050036)
			(end -0.8001 1.050036)
			(stroke
				(width 0.1)
				(type default)
			)
			(layer "F.Fab")
		)
		(fp_line
			(start 0.8001 -1.050036)
			(end 0.8001 1.050036)
			(stroke
				(width 0.1)
				(type default)
			)
			(layer "F.Fab")
		)
		(fp_line
			(start -0.8001 1.050036)
			(end -0.8001 -1.050036)
			(stroke
				(width 0.1)
				(type default)
			)
			(layer "F.Fab")
		)
		(fp_line
			(start -0.8001 -1.050036)
			(end 0.8001 -1.050036)
			(stroke
				(width 0.1)
				(type default)
			)
			(layer "F.Fab")
		)
		(fp_poly
			(pts
				(xy -2.458974 -0.508) (xy -2.458974 0.508) (xy -1.442974 0)
			)
			(stroke
				(width 0)
				(type default)
			)
			(fill yes)
			(layer "F.Fab")
		)
		(pad "1_2" smd circle
			(at -0.374904 0 270)
			(size 0 0)
			(layers "F.Cu" "F.Mask" "F.Paste")
			(net "P12V_AUX")
		)
		(pad "3" smd rect
			(at -0.499872 0.999998 180)
			(size 0.254 0.7112)
			(layers "F.Cu" "F.Mask" "F.Paste")
			(net "GND")
		)
		(pad "4" smd rect
			(at 0 0.999998 180)
			(size 0.254 0.7112)
			(layers "F.Cu" "F.Mask" "F.Paste")
			(net "P12V_SSD8_CO_ILIMIT")
		)
		(pad "5" smd rect
			(at 0.499872 0.999998 180)
			(size 0.254 0.7112)
			(layers "F.Cu" "F.Mask" "F.Paste")
			(net "P12V_SSD8_CO_MODE")
		)
		(pad "6_7" smd circle
			(at 0.374904 0 90)
			(size 0 0)
			(layers "F.Cu" "F.Mask" "F.Paste")
			(net "P12V_SSD8_R")
		)
		(pad "8" smd rect
			(at 0.499872 -0.999998 180)
			(size 0.254 0.7112)
			(layers "F.Cu" "F.Mask" "F.Paste")
			(net "P12V_SSD8_CO_GATE")
		)
		(pad "9" smd rect
			(at 0 -0.999998 180)
			(size 0.254 0.7112)
			(layers "F.Cu" "F.Mask" "F.Paste")
			(net "P12V_SSD8_CO_EN")
		)
		(pad "10" smd rect
			(at -0.499872 -0.999998 180)
			(size 0.254 0.7112)
			(layers "F.Cu" "F.Mask" "F.Paste")
			(net "P12V_SSD8_CO_DV_DT")
		)
	)
	(footprint ""
		(layer "F.Cu")
		(at 406.484582 -367.02619 -90)
		(property "Reference" "R6677"
			(at 0 0 270)
			(layer "F.SilkS")
			(hide yes)
			(effects
				(font
					(size 1.27 1.27)
				)
			)
		)
		(property "Value" ""
			(at 0 0 270)
			(layer "F.Fab")
			(effects
				(font
					(size 1.27 1.27)
				)
			)
		)
		(duplicate_pad_numbers_are_jumpers no)
		(fp_line
			(start -0.7874 0.4064)
			(end -0.7874 -0.4064)
			(stroke
				(width 0.1524)
				(type default)
			)
			(layer "F.SilkS")
		)
		(fp_line
			(start 0.7874 0.4064)
			(end -0.7874 0.4064)
			(stroke
				(width 0.1524)
				(type default)
			)
			(layer "F.SilkS")
		)
		(fp_line
			(start -0.7874 -0.4064)
			(end 0.7874 -0.4064)
			(stroke
				(width 0.1524)
				(type default)
			)
			(layer "F.SilkS")
		)
		(fp_line
			(start 0.7874 -0.4064)
			(end 0.7874 0.4064)
			(stroke
				(width 0.1524)
				(type default)
			)
			(layer "F.SilkS")
		)
		(fp_line
			(start -0.67945 0.3048)
			(end -0.67945 -0.305054)
			(stroke
				(width 0.1)
				(type default)
			)
			(layer "F.Fab")
		)
		(fp_line
			(start -0.12065 0.3048)
			(end -0.67945 0.3048)
			(stroke
				(width 0.1)
				(type default)
			)
			(layer "F.Fab")
		)
		(fp_line
			(start 0.120396 0.3048)
			(end 0.120396 0.2794)
			(stroke
				(width 0.1)
				(type default)
			)
			(layer "F.Fab")
		)
		(fp_line
			(start 0.67945 0.3048)
			(end 0.120396 0.3048)
			(stroke
				(width 0.1)
				(type default)
			)
			(layer "F.Fab")
		)
		(fp_line
			(start -0.12065 0.2794)
			(end -0.12065 0.3048)
			(stroke
				(width 0.1)
				(type default)
			)
			(layer "F.Fab")
		)
		(fp_line
			(start 0.120396 0.2794)
			(end -0.12065 0.2794)
			(stroke
				(width 0.1)
				(type default)
			)
			(layer "F.Fab")
		)
		(fp_line
			(start -0.12065 -0.2794)
			(end 0.12065 -0.2794)
			(stroke
				(width 0.1)
				(type default)
			)
			(layer "F.Fab")
		)
		(fp_line
			(start 0.12065 -0.2794)
			(end 0.12065 -0.3048)
			(stroke
				(width 0.1)
				(type default)
			)
			(layer "F.Fab")
		)
		(fp_line
			(start 0.12065 -0.3048)
			(end 0.67945 -0.3048)
			(stroke
				(width 0.1)
				(type default)
			)
			(layer "F.Fab")
		)
		(fp_line
			(start 0.67945 -0.3048)
			(end 0.67945 0.3048)
			(stroke
				(width 0.1)
				(type default)
			)
			(layer "F.Fab")
		)
		(fp_line
			(start -0.67945 -0.305054)
			(end -0.12065 -0.305054)
			(stroke
				(width 0.1)
				(type default)
			)
			(layer "F.Fab")
		)
		(fp_line
			(start -0.12065 -0.305054)
			(end -0.12065 -0.2794)
			(stroke
				(width 0.1)
				(type default)
			)
			(layer "F.Fab")
		)
		(pad "1" smd circle
			(at -0.40005 0 270)
			(size 0 0)
			(layers "F.Cu" "F.Mask" "F.Paste")
			(net "GPU_3V3IO_RSVD1_N")
		)
		(pad "2" smd circle
			(at 0.40005 0 270)
			(size 0 0)
			(layers "F.Cu" "F.Mask" "F.Paste")
			(net "P3V3_AUX")
		)
	)
	(footprint ""
		(layer "F.Cu")
		(at 322.611242 -107.29976)
		(property "Reference" "R738"
			(at 0 0 0)
			(layer "F.SilkS")
			(hide yes)
			(effects
				(font
					(size 1.27 1.27)
				)
			)
		)
		(property "Value" ""
			(at 0 0 0)
			(layer "F.Fab")
			(effects
				(font
					(size 1.27 1.27)
				)
			)
		)
		(duplicate_pad_numbers_are_jumpers no)
		(fp_line
			(start -3.937508 -1.8796)
			(end -3.937508 1.8796)
			(stroke
				(width 0.1524)
				(type default)
			)
			(layer "F.SilkS")
		)
		(fp_line
			(start -3.937508 1.8796)
			(end 3.937508 1.8796)
			(stroke
				(width 0.1524)
				(type default)
			)
			(layer "F.SilkS")
		)
		(fp_line
			(start 3.937508 -1.8796)
			(end -3.937508 -1.8796)
			(stroke
				(width 0.1524)
				(type default)
			)
			(layer "F.SilkS")
		)
		(fp_line
			(start 3.937508 1.8796)
			(end 3.937508 -1.8796)
			(stroke
				(width 0.1524)
				(type default)
			)
			(layer "F.SilkS")
		)
		(fp_line
			(start -3.275076 -1.674876)
			(end -3.275076 1.674876)
			(stroke
				(width 0.1)
				(type default)
			)
			(layer "F.Fab")
		)
		(fp_line
			(start -3.275076 1.674876)
			(end 3.275076 1.674876)
			(stroke
				(width 0.1)
				(type default)
			)
			(layer "F.Fab")
		)
		(fp_line
			(start 3.275076 -1.674876)
			(end -3.275076 -1.674876)
			(stroke
				(width 0.1)
				(type default)
			)
			(layer "F.Fab")
		)
		(fp_line
			(start 3.275076 1.674876)
			(end 3.275076 -1.674876)
			(stroke
				(width 0.1)
				(type default)
			)
			(layer "F.Fab")
		)
		(pad "1" smd rect
			(at -2.350008 0)
			(size 2.921 3.5052)
			(layers "F.Cu" "F.Mask" "F.Paste")
			(net "P12V_NIC5")
		)
		(pad "2" smd rect
			(at 2.350008 0)
			(size 2.921 3.5052)
			(layers "F.Cu" "F.Mask" "F.Paste")
			(net "P12V_NIC5_R")
		)
	)
	(footprint ""
		(layer "F.Cu")
		(at 210.475322 -227.225606 -90)
		(property "Reference" "C2569"
			(at 0 0 270)
			(layer "F.SilkS")
			(hide yes)
			(effects
				(font
					(size 1.27 1.27)
				)
			)
		)
		(property "Value" ""
			(at 0 0 270)
			(layer "F.Fab")
			(effects
				(font
					(size 1.27 1.27)
				)
			)
		)
		(duplicate_pad_numbers_are_jumpers no)
		(fp_line
			(start -0.7874 0.4064)
			(end -0.7874 -0.4064)
			(stroke
				(width 0.1524)
				(type default)
			)
			(layer "F.SilkS")
		)
		(fp_line
			(start 0.7874 0.4064)
			(end -0.7874 0.4064)
			(stroke
				(width 0.1524)
				(type default)
			)
			(layer "F.SilkS")
		)
		(fp_line
			(start -0.7874 -0.4064)
			(end 0.7874 -0.4064)
			(stroke
				(width 0.1524)
				(type default)
			)
			(layer "F.SilkS")
		)
		(fp_line
			(start 0.7874 -0.4064)
			(end 0.7874 0.4064)
			(stroke
				(width 0.1524)
				(type default)
			)
			(layer "F.SilkS")
		)
		(fp_line
			(start -0.67945 0.3048)
			(end -0.67945 -0.305054)
			(stroke
				(width 0.1)
				(type default)
			)
			(layer "F.Fab")
		)
		(fp_line
			(start -0.12065 0.3048)
			(end -0.67945 0.3048)
			(stroke
				(width 0.1)
				(type default)
			)
			(layer "F.Fab")
		)
		(fp_line
			(start 0.120396 0.3048)
			(end 0.120396 0.2794)
			(stroke
				(width 0.1)
				(type default)
			)
			(layer "F.Fab")
		)
		(fp_line
			(start 0.67945 0.3048)
			(end 0.120396 0.3048)
			(stroke
				(width 0.1)
				(type default)
			)
			(layer "F.Fab")
		)
		(fp_line
			(start -0.12065 0.2794)
			(end -0.12065 0.3048)
			(stroke
				(width 0.1)
				(type default)
			)
			(layer "F.Fab")
		)
		(fp_line
			(start 0.120396 0.2794)
			(end -0.12065 0.2794)
			(stroke
				(width 0.1)
				(type default)
			)
			(layer "F.Fab")
		)
		(fp_line
			(start -0.12065 -0.2794)
			(end 0.12065 -0.2794)
			(stroke
				(width 0.1)
				(type default)
			)
			(layer "F.Fab")
		)
		(fp_line
			(start 0.12065 -0.2794)
			(end 0.12065 -0.3048)
			(stroke
				(width 0.1)
				(type default)
			)
			(layer "F.Fab")
		)
		(fp_line
			(start 0.12065 -0.3048)
			(end 0.67945 -0.3048)
			(stroke
				(width 0.1)
				(type default)
			)
			(layer "F.Fab")
		)
		(fp_line
			(start 0.67945 -0.3048)
			(end 0.67945 0.3048)
			(stroke
				(width 0.1)
				(type default)
			)
			(layer "F.Fab")
		)
		(fp_line
			(start -0.67945 -0.305054)
			(end -0.12065 -0.305054)
			(stroke
				(width 0.1)
				(type default)
			)
			(layer "F.Fab")
		)
		(fp_line
			(start -0.12065 -0.305054)
			(end -0.12065 -0.2794)
			(stroke
				(width 0.1)
				(type default)
			)
			(layer "F.Fab")
		)
		(pad "1" smd circle
			(at -0.40005 0 270)
			(size 0 0)
			(layers "F.Cu" "F.Mask" "F.Paste")
			(net "GND")
		)
		(pad "2" smd circle
			(at 0.40005 0 270)
			(size 0 0)
			(layers "F.Cu" "F.Mask" "F.Paste")
			(net "P3V3_AUX")
		)
	)
	(footprint ""
		(layer "F.Cu")
		(at 312.739532 -137.645648)
		(property "Reference" "R260"
			(at 0 0 0)
			(layer "F.SilkS")
			(hide yes)
			(effects
				(font
					(size 1.27 1.27)
				)
			)
		)
		(property "Value" ""
			(at 0 0 0)
			(layer "F.Fab")
			(effects
				(font
					(size 1.27 1.27)
				)
			)
		)
		(duplicate_pad_numbers_are_jumpers no)
		(fp_line
			(start -0.7874 -0.4064)
			(end 0.7874 -0.4064)
			(stroke
				(width 0.1524)
				(type default)
			)
			(layer "F.SilkS")
		)
		(fp_line
			(start -0.7874 0.4064)
			(end -0.7874 -0.4064)
			(stroke
				(width 0.1524)
				(type default)
			)
			(layer "F.SilkS")
		)
		(fp_line
			(start 0.7874 -0.4064)
			(end 0.7874 0.4064)
			(stroke
				(width 0.1524)
				(type default)
			)
			(layer "F.SilkS")
		)
		(fp_line
			(start 0.7874 0.4064)
			(end -0.7874 0.4064)
			(stroke
				(width 0.1524)
				(type default)
			)
			(layer "F.SilkS")
		)
		(fp_line
			(start -0.67945 -0.305054)
			(end -0.12065 -0.305054)
			(stroke
				(width 0.1)
				(type default)
			)
			(layer "F.Fab")
		)
		(fp_line
			(start -0.67945 0.3048)
			(end -0.67945 -0.305054)
			(stroke
				(width 0.1)
				(type default)
			)
			(layer "F.Fab")
		)
		(fp_line
			(start -0.12065 -0.305054)
			(end -0.12065 -0.2794)
			(stroke
				(width 0.1)
				(type default)
			)
			(layer "F.Fab")
		)
		(fp_line
			(start -0.12065 -0.2794)
			(end 0.12065 -0.2794)
			(stroke
				(width 0.1)
				(type default)
			)
			(layer "F.Fab")
		)
		(fp_line
			(start -0.12065 0.2794)
			(end -0.12065 0.3048)
			(stroke
				(width 0.1)
				(type default)
			)
			(layer "F.Fab")
		)
		(fp_line
			(start -0.12065 0.3048)
			(end -0.67945 0.3048)
			(stroke
				(width 0.1)
				(type default)
			)
			(layer "F.Fab")
		)
		(fp_line
			(start 0.120396 0.2794)
			(end -0.12065 0.2794)
			(stroke
				(width 0.1)
				(type default)
			)
			(layer "F.Fab")
		)
		(fp_line
			(start 0.120396 0.3048)
			(end 0.120396 0.2794)
			(stroke
				(width 0.1)
				(type default)
			)
			(layer "F.Fab")
		)
		(fp_line
			(start 0.12065 -0.3048)
			(end 0.67945 -0.3048)
			(stroke
				(width 0.1)
				(type default)
			)
			(layer "F.Fab")
		)
		(fp_line
			(start 0.12065 -0.2794)
			(end 0.12065 -0.3048)
			(stroke
				(width 0.1)
				(type default)
			)
			(layer "F.Fab")
		)
		(fp_line
			(start 0.67945 -0.3048)
			(end 0.67945 0.3048)
			(stroke
				(width 0.1)
				(type default)
			)
			(layer "F.Fab")
		)
		(fp_line
			(start 0.67945 0.3048)
			(end 0.120396 0.3048)
			(stroke
				(width 0.1)
				(type default)
			)
			(layer "F.Fab")
		)
		(pad "1" smd circle
			(at -0.40005 0)
			(size 0 0)
			(layers "F.Cu" "F.Mask" "F.Paste")
			(net "PRSNTB0_NIC5_N")
		)
		(pad "2" smd circle
			(at 0.40005 0)
			(size 0 0)
			(layers "F.Cu" "F.Mask" "F.Paste")
			(net "P3V3_AUX")
		)
	)
	(footprint ""
		(layer "F.Cu")
		(at 334.130396 -121.80824 180)
		(property "Reference" "R6041"
			(at 0 0 180)
			(layer "F.SilkS")
			(hide yes)
			(effects
				(font
					(size 1.27 1.27)
				)
			)
		)
		(property "Value" ""
			(at 0 0 180)
			(layer "F.Fab")
			(effects
				(font
					(size 1.27 1.27)
				)
			)
		)
		(duplicate_pad_numbers_are_jumpers no)
		(fp_line
			(start 0.7874 0.4064)
			(end -0.7874 0.4064)
			(stroke
				(width 0.1524)
				(type default)
			)
			(layer "F.SilkS")
		)
		(fp_line
			(start 0.7874 -0.4064)
			(end 0.7874 0.4064)
			(stroke
				(width 0.1524)
				(type default)
			)
			(layer "F.SilkS")
		)
		(fp_line
			(start -0.7874 0.4064)
			(end -0.7874 -0.4064)
			(stroke
				(width 0.1524)
				(type default)
			)
			(layer "F.SilkS")
		)
		(fp_line
			(start -0.7874 -0.4064)
			(end 0.7874 -0.4064)
			(stroke
				(width 0.1524)
				(type default)
			)
			(layer "F.SilkS")
		)
		(fp_line
			(start 0.67945 0.3048)
			(end 0.120396 0.3048)
			(stroke
				(width 0.1)
				(type default)
			)
			(layer "F.Fab")
		)
		(fp_line
			(start 0.67945 -0.3048)
			(end 0.67945 0.3048)
			(stroke
				(width 0.1)
				(type default)
			)
			(layer "F.Fab")
		)
		(fp_line
			(start 0.12065 -0.2794)
			(end 0.12065 -0.3048)
			(stroke
				(width 0.1)
				(type default)
			)
			(layer "F.Fab")
		)
		(fp_line
			(start 0.12065 -0.3048)
			(end 0.67945 -0.3048)
			(stroke
				(width 0.1)
				(type default)
			)
			(layer "F.Fab")
		)
		(fp_line
			(start 0.120396 0.3048)
			(end 0.120396 0.2794)
			(stroke
				(width 0.1)
				(type default)
			)
			(layer "F.Fab")
		)
		(fp_line
			(start 0.120396 0.2794)
			(end -0.12065 0.2794)
			(stroke
				(width 0.1)
				(type default)
			)
			(layer "F.Fab")
		)
		(fp_line
			(start -0.12065 0.3048)
			(end -0.67945 0.3048)
			(stroke
				(width 0.1)
				(type default)
			)
			(layer "F.Fab")
		)
		(fp_line
			(start -0.12065 0.2794)
			(end -0.12065 0.3048)
			(stroke
				(width 0.1)
				(type default)
			)
			(layer "F.Fab")
		)
		(fp_line
			(start -0.12065 -0.2794)
			(end 0.12065 -0.2794)
			(stroke
				(width 0.1)
				(type default)
			)
			(layer "F.Fab")
		)
		(fp_line
			(start -0.12065 -0.305054)
			(end -0.12065 -0.2794)
			(stroke
				(width 0.1)
				(type default)
			)
			(layer "F.Fab")
		)
		(fp_line
			(start -0.67945 0.3048)
			(end -0.67945 -0.305054)
			(stroke
				(width 0.1)
				(type default)
			)
			(layer "F.Fab")
		)
		(fp_line
			(start -0.67945 -0.305054)
			(end -0.12065 -0.305054)
			(stroke
				(width 0.1)
				(type default)
			)
			(layer "F.Fab")
		)
		(pad "1" smd circle
			(at -0.40005 0 180)
			(size 0 0)
			(layers "F.Cu" "F.Mask" "F.Paste")
			(net "P3V3_NIC5_PG_G1")
		)
		(pad "2" smd circle
			(at 0.40005 0 180)
			(size 0 0)
			(layers "F.Cu" "F.Mask" "F.Paste")
			(net "GND")
		)
	)
)
